#ISCELL
  pure_quanta quanta_title_block_c *
  *
#ISCELL
  standard offpage *
  page115_i1
#ISCELL
  logical_power universal_power *
  page115_i10
#CELL
  pure_quanta q_res *
  page115_i11
#CELL
  pure_quanta q_res *
  page115_i12
#ISCELL
  logical_power universal_power *
  page115_i13
#CELL
  pure_quanta q_res *
  page115_i14
#ISCELL
  logical_power universal_power *
  page115_i15
#CELL
  pure_quanta q_res *
  page115_i16
#CELL
  pure_quanta q_res *
  page115_i17
#CELL
  pure_quanta q_res *
  page115_i18
#CELL
  pure_quanta q_res *
  page115_i19
#ISCELL
  standard offpage *
  page115_i2
#ISCELL
  logical_power universal_power *
  page115_i20
#CELL
  pure_quanta schottky_12 *
  page115_i22
#ISCELL
  logical_power universal_power *
  page115_i24
#CELL
  pure_quanta schottky_12 *
  page115_i25
#CELL
  pure_quanta schottky_12 *
  page115_i27
#CELL
  pure_quanta schottky_12 *
  page115_i29
#ISCELL
  standard offpage *
  page115_i3
#ISCELL
  logical_power universal_power *
  page115_i30
#ISCELL
  logical_power universal_power *
  page115_i31
#ISCELL
  logical_power universal_power *
  page115_i32
#ISCELL
  standard offpage *
  page115_i33
#ISCELL
  standard offpage *
  page115_i34
#ISCELL
  standard offpage *
  page115_i35
#ISCELL
  standard offpage *
  page115_i36
#CELL
  pure_quanta q_res *
  page115_i37
#CELL
  pure_quanta q_res *
  page115_i38
#ISCELL
  logical_power universal_power *
  page115_i39
#ISCELL
  standard offpage *
  page115_i4
#CELL
  pure_quanta q_res *
  page115_i40
#CELL
  pure_quanta q_res *
  page115_i41
#CELL
  pure_quanta q_res *
  page115_i42
#ISCELL
  logical_power universal_power *
  page115_i43
#ISCELL
  logical_power universal_power *
  page115_i44
#CELL
  pure_quanta q_res *
  page115_i45
#CELL
  pure_quanta q_res *
  page115_i46
#ISCELL
  logical_power universal_power *
  page115_i47
#CELL
  pure_quanta q_res *
  page115_i48
#ISCELL
  standard offpage *
  page115_i5
#CELL
  pure_quanta schottky_12 *
  page115_i50
#CELL
  pure_quanta schottky_12 *
  page115_i52
#CELL
  pure_quanta schottky_12 *
  page115_i54
#ISCELL
  logical_power universal_power *
  page115_i56
#ISCELL
  logical_power universal_power *
  page115_i57
#ISCELL
  logical_power universal_power *
  page115_i58
#CELL
  pure_quanta schottky_12 *
  page115_i59
#ISCELL
  standard offpage *
  page115_i6
#ISCELL
  logical_power universal_power *
  page115_i60
#ISCELL
  standard offpage *
  page115_i61
#ISCELL
  standard offpage *
  page115_i62
#ISCELL
  standard offpage *
  page115_i63
#ISCELL
  standard offpage *
  page115_i64
#CELL
  pure_quanta q_res *
  page115_i65
#CELL
  pure_quanta q_res *
  page115_i66
#CELL
  pure_quanta q_res *
  page115_i67
#CELL
  pure_quanta q_res *
  page115_i68
#CELL
  pure_quanta q_res *
  page115_i69
#ISCELL
  standard offpage *
  page115_i7
#CELL
  pure_quanta q_res *
  page115_i70
#CELL
  pure_quanta q_res *
  page115_i71
#CELL
  pure_quanta q_res *
  page115_i72
#ISCELL
  standard offpage *
  page115_i8
#CELL
  pure_quanta q_res *
  page115_i9
